(kicad_pcb
	(version 20260206)
	(generator "pcbnew")
	(generator_version "10.0")
	(general
		(thickness 1.6)
		(legacy_teardrops no)
	)
	(paper "A4")
	(title_block
		(title "timecard-production-celestica-r4006 — R4006-B0001-02_R01.brd")
		(comment 1 "Time Appliance Project (Time Card) / footprints 561-566 of 1113")
	)
	(layers
		(0 "F.Cu" signal "TOP")
		(4 "In1.Cu" signal "L02_GND1")
		(6 "In2.Cu" signal "L03_SIG1")
		(8 "In3.Cu" signal "L04_GND2")
		(10 "In4.Cu" signal "L05_VCC1")
		(12 "In5.Cu" signal "L06_VCC2")
		(14 "In6.Cu" signal "L07_GND3")
		(16 "In7.Cu" signal "L08_SIG2")
		(18 "In8.Cu" signal "L09_GND4")
		(2 "B.Cu" signal "BOTTOM")
		(9 "F.Adhes" user "F.Adhesive")
		(11 "B.Adhes" user "B.Adhesive")
		(13 "F.Paste" user "Package Geometry/Pastemask Top")
		(15 "B.Paste" user "Package Geometry/Pastemask Bottom")
		(5 "F.SilkS" user "Ref Des/Silkscreen Top")
		(7 "B.SilkS" user "Ref Des/Silkscreen Bottom")
		(1 "F.Mask" user "Board Geometry/Soldermask Top")
		(3 "B.Mask" user "Board Geometry/Soldermask Bottom")
		(17 "Dwgs.User" user "User.Drawings")
		(19 "Cmts.User" user "User.Comments")
		(21 "Eco1.User" user "User.Eco1")
		(23 "Eco2.User" user "User.Eco2")
		(25 "Edge.Cuts" user "Board Geometry/Outline")
		(27 "Margin" user)
		(31 "F.CrtYd" user "Package Geometry/Place Bound Top")
		(29 "B.CrtYd" user "Package Geometry/Place Bound Bottom")
		(35 "F.Fab" user "Ref Des/Assembly Top")
		(33 "B.Fab" user "Ref Des/Assembly Bottom")
	)
	(footprint ""
		(layer "F.Cu")
		(at 118.346982 -41.32326)
		(property "Reference" "TP141"
			(at 0 0 0)
			(layer "F.SilkS")
			(hide yes)
			(effects
				(font
					(size 1.27 1.27)
				)
			)
		)
		(property "Value" ""
			(at 0 0 0)
			(layer "F.Fab")
			(effects
				(font
					(size 1.27 1.27)
				)
			)
		)
		(property "Device Type" "TP_PIONT-TP010CT020B030_PTH-TPA"
			(at -1.341882 0.996696 0)
			(unlocked yes)
			(layer "F.Fab")
			(hide yes)
			(effects
				(font
					(size 0.7874 0.5842)
					(thickness 0.1524)
				)
				(justify left)
			)
		)
		(duplicate_pad_numbers_are_jumpers no)
		(fp_poly
			(pts
				(arc
					(start 0.889 0)
					(mid -0.889 0)
					(end 0.889 0)
				)
			)
			(stroke
				(width 0)
				(type default)
			)
			(fill no)
			(layer "B.CrtYd")
		)
		(fp_poly
			(pts
				(arc
					(start 0.889 0)
					(mid -0.889 0)
					(end 0.889 0)
				)
			)
			(stroke
				(width 0)
				(type default)
			)
			(fill no)
			(layer "F.CrtYd")
		)
		(pad "1" thru_hole circle
			(at 0 0)
			(size 0.508 0.508)
			(drill 0.254)
			(layers "*.Cu" "*.Mask")
			(remove_unused_layers no)
			(net "IO_L24N_34")
			(clearance 0.1016)
			(padstack
				(mode front_inner_back)
				(layer "Inner"
					(shape circle)
					(size 0.508 0.508)
					(clearance 0.1016)
				)
				(layer "B.Cu"
					(shape circle)
					(size 0.762 0.762)
					(clearance -0.0254)
				)
			)
		)
	)
	(footprint ""
		(layer "F.Cu")
		(at 52.9082 -74.9808 90)
		(property "Reference" "R408"
			(at -0.5588 4.53517 90)
			(unlocked yes)
			(layer "F.SilkS")
			(effects
				(font
					(size 0.7874 0.5842)
					(thickness 0.1524)
				)
			)
		)
		(property "Value" "VAL*"
			(at 0.02032 2.13233 90)
			(unlocked yes)
			(layer "F.Fab")
			(hide yes)
			(effects
				(font
					(size 0.7874 0.5842)
					(thickness 0.1524)
				)
			)
		)
		(property "Device Type" "RESISTOR-G155-14701-01,4.7KOHMA"
			(at 0.008382 1.210564 90)
			(unlocked yes)
			(layer "F.Fab")
			(hide yes)
			(effects
				(font
					(size 0.7874 0.5842)
					(thickness 0.1524)
				)
			)
		)
		(property "User Part Number" "PARTNUM*"
			(at 0.02032 4.024884 90)
			(unlocked yes)
			(layer "Cmts.User")
			(hide yes)
			(effects
				(font
					(size 0.7874 0.5842)
					(thickness 0.1524)
				)
			)
		)
		(property "Tolerance" "TOL*"
			(at 0.044704 3.05435 90)
			(unlocked yes)
			(layer "Cmts.User")
			(hide yes)
			(effects
				(font
					(size 0.7874 0.5842)
					(thickness 0.1524)
				)
			)
		)
		(duplicate_pad_numbers_are_jumpers no)
		(fp_line
			(start 1.143 -0.5588)
			(end -1.143 -0.5588)
			(stroke
				(width 0.1)
				(type default)
			)
			(layer "F.SilkS")
		)
		(fp_line
			(start -1.143 -0.5588)
			(end -1.143 0.5588)
			(stroke
				(width 0.1)
				(type default)
			)
			(layer "F.SilkS")
		)
		(fp_line
			(start 1.143 0.5588)
			(end 1.143 -0.5588)
			(stroke
				(width 0.1)
				(type default)
			)
			(layer "F.SilkS")
		)
		(fp_line
			(start -1.143 0.5588)
			(end 1.143 0.5588)
			(stroke
				(width 0.1)
				(type default)
			)
			(layer "F.SilkS")
		)
		(fp_rect
			(start -1.143 0.5588)
			(end 1.143 -0.5588)
			(stroke
				(width 0)
				(type default)
			)
			(fill no)
			(layer "F.CrtYd")
		)
		(fp_line
			(start 0.508 -0.3048)
			(end -0.508 -0.3048)
			(stroke
				(width 0.1)
				(type default)
			)
			(layer "F.Fab")
		)
		(fp_line
			(start -0.508 -0.3048)
			(end -0.508 0.3048)
			(stroke
				(width 0.1)
				(type default)
			)
			(layer "F.Fab")
		)
		(fp_line
			(start 0.508 0.3048)
			(end 0.508 -0.3048)
			(stroke
				(width 0.1)
				(type default)
			)
			(layer "F.Fab")
		)
		(fp_line
			(start -0.508 0.3048)
			(end 0.508 0.3048)
			(stroke
				(width 0.1)
				(type default)
			)
			(layer "F.Fab")
		)
		(pad "1" smd rect
			(at -0.5334 0 90)
			(size 0.7112 0.6096)
			(layers "F.Cu" "F.Mask" "F.Paste")
			(net "XP3R3V_FPGA")
		)
		(pad "2" smd rect
			(at 0.5334 0 90)
			(size 0.7112 0.6096)
			(layers "F.Cu" "F.Mask" "F.Paste")
			(net "UNNAMED_6_LM75BDPTSSOP8_I59_A2")
		)
		(zone
			(layer "F.Cu")
			(hatch none 0.5)
			(connect_pads
				(clearance 0)
			)
			(min_thickness 0.25)
			(keepout
				(tracks allowed)
				(vias not_allowed)
				(pads allowed)
				(copperpour not_allowed)
				(footprints allowed)
			)
			(placement
				(enabled no)
				(sheetname "")
			)
			(fill
				(thermal_gap 0.5)
				(thermal_bridge_width 0.5)
				(island_removal_mode 0)
			)
			(polygon
				(pts
					(xy 53.213 -74.9046) (xy 53.213 -75.057) (xy 52.6034 -75.057) (xy 52.6034 -74.9046)
				)
			)
		)
		(zone
			(layer "F.Cu")
			(hatch none 0.5)
			(connect_pads
				(clearance 0)
			)
			(min_thickness 0.25)
			(keepout
				(tracks not_allowed)
				(vias allowed)
				(pads allowed)
				(copperpour not_allowed)
				(footprints allowed)
			)
			(placement
				(enabled no)
				(sheetname "")
			)
			(fill
				(thermal_gap 0.5)
				(thermal_bridge_width 0.5)
				(island_removal_mode 0)
			)
			(polygon
				(pts
					(xy 53.213 -74.9046) (xy 53.213 -75.057) (xy 52.6034 -75.057) (xy 52.6034 -74.9046)
				)
			)
		)
	)
	(footprint ""
		(layer "F.Cu")
		(at 126.365 -37.719)
		(property "Reference" "TP135"
			(at 2.95275 2.2098 90)
			(unlocked yes)
			(layer "F.SilkS")
			(effects
				(font
					(size 0.635 0.4064)
					(thickness 0.1524)
				)
				(justify left)
			)
		)
		(property "Value" ""
			(at 0 0 0)
			(layer "F.Fab")
			(effects
				(font
					(size 1.27 1.27)
				)
			)
		)
		(property "Device Type" "TP_PIONT-TP010CT020B030_PTH-TPA"
			(at -1.341882 0.996696 0)
			(unlocked yes)
			(layer "F.Fab")
			(hide yes)
			(effects
				(font
					(size 0.7874 0.5842)
					(thickness 0.1524)
				)
				(justify left)
			)
		)
		(duplicate_pad_numbers_are_jumpers no)
		(fp_poly
			(pts
				(arc
					(start 0.889 0)
					(mid -0.889 0)
					(end 0.889 0)
				)
			)
			(stroke
				(width 0)
				(type default)
			)
			(fill no)
			(layer "B.CrtYd")
		)
		(fp_poly
			(pts
				(arc
					(start 0.889 0)
					(mid -0.889 0)
					(end 0.889 0)
				)
			)
			(stroke
				(width 0)
				(type default)
			)
			(fill no)
			(layer "F.CrtYd")
		)
		(pad "1" thru_hole circle
			(at 0 0)
			(size 0.508 0.508)
			(drill 0.254)
			(layers "*.Cu" "*.Mask")
			(remove_unused_layers no)
			(net "IO_L21N_34")
			(clearance 0.1016)
			(padstack
				(mode front_inner_back)
				(layer "Inner"
					(shape circle)
					(size 0.508 0.508)
					(clearance 0.1016)
				)
				(layer "B.Cu"
					(shape circle)
					(size 0.762 0.762)
					(clearance -0.0254)
				)
			)
		)
	)
	(footprint ""
		(layer "F.Cu")
		(at 66.4464 -16.637 180)
		(property "Reference" "R55"
			(at -0.9906 1.23063 0)
			(unlocked yes)
			(layer "F.SilkS")
			(effects
				(font
					(size 0.7874 0.5842)
					(thickness 0.1524)
				)
			)
		)
		(property "Value" "VAL*"
			(at 0.02032 2.13233 180)
			(unlocked yes)
			(layer "F.Fab")
			(hide yes)
			(effects
				(font
					(size 0.7874 0.5842)
					(thickness 0.1524)
				)
			)
		)
		(property "Tolerance" "TOL*"
			(at 0.044704 3.05435 180)
			(unlocked yes)
			(layer "Cmts.User")
			(hide yes)
			(effects
				(font
					(size 0.7874 0.5842)
					(thickness 0.1524)
				)
			)
		)
		(property "User Part Number" "PARTNUM*"
			(at 0.02032 4.024884 180)
			(unlocked yes)
			(layer "Cmts.User")
			(hide yes)
			(effects
				(font
					(size 0.7874 0.5842)
					(thickness 0.1524)
				)
			)
		)
		(property "Device Type" "RESISTOR-G155-14701-01,4.7KOHMA"
			(at 0.008382 1.210564 180)
			(unlocked yes)
			(layer "F.Fab")
			(hide yes)
			(effects
				(font
					(size 0.7874 0.5842)
					(thickness 0.1524)
				)
			)
		)
		(duplicate_pad_numbers_are_jumpers no)
		(fp_line
			(start 1.143 0.5588)
			(end 1.143 -0.5588)
			(stroke
				(width 0.1)
				(type default)
			)
			(layer "F.SilkS")
		)
		(fp_line
			(start 1.143 -0.5588)
			(end -1.143 -0.5588)
			(stroke
				(width 0.1)
				(type default)
			)
			(layer "F.SilkS")
		)
		(fp_line
			(start -1.143 0.5588)
			(end 1.143 0.5588)
			(stroke
				(width 0.1)
				(type default)
			)
			(layer "F.SilkS")
		)
		(fp_line
			(start -1.143 -0.5588)
			(end -1.143 0.5588)
			(stroke
				(width 0.1)
				(type default)
			)
			(layer "F.SilkS")
		)
		(fp_rect
			(start 1.143 -0.5588)
			(end -1.143 0.5588)
			(stroke
				(width 0)
				(type default)
			)
			(fill no)
			(layer "F.CrtYd")
		)
		(fp_line
			(start 0.508 0.3048)
			(end 0.508 -0.3048)
			(stroke
				(width 0.1)
				(type default)
			)
			(layer "F.Fab")
		)
		(fp_line
			(start 0.508 -0.3048)
			(end -0.508 -0.3048)
			(stroke
				(width 0.1)
				(type default)
			)
			(layer "F.Fab")
		)
		(fp_line
			(start -0.508 0.3048)
			(end 0.508 0.3048)
			(stroke
				(width 0.1)
				(type default)
			)
			(layer "F.Fab")
		)
		(fp_line
			(start -0.508 -0.3048)
			(end -0.508 0.3048)
			(stroke
				(width 0.1)
				(type default)
			)
			(layer "F.Fab")
		)
		(pad "1" smd rect
			(at -0.5334 0 180)
			(size 0.7112 0.6096)
			(layers "F.Cu" "F.Mask" "F.Paste")
			(net "PCIE_CONN_PERST_N")
		)
		(pad "2" smd rect
			(at 0.5334 0 180)
			(size 0.7112 0.6096)
			(layers "F.Cu" "F.Mask" "F.Paste")
			(net "SG")
		)
		(zone
			(layer "F.Cu")
			(hatch none 0.5)
			(connect_pads
				(clearance 0)
			)
			(min_thickness 0.25)
			(keepout
				(tracks allowed)
				(vias not_allowed)
				(pads allowed)
				(copperpour not_allowed)
				(footprints allowed)
			)
			(placement
				(enabled no)
				(sheetname "")
			)
			(fill
				(thermal_gap 0.5)
				(thermal_bridge_width 0.5)
				(island_removal_mode 0)
			)
			(polygon
				(pts
					(xy 66.3702 -16.3322) (xy 66.5226 -16.3322) (xy 66.5226 -16.9418) (xy 66.3702 -16.9418)
				)
			)
		)
	)
	(footprint ""
		(layer "F.Cu")
		(at 111.125 -98.171 180)
		(property "Reference" "R320"
			(at -3.302 3.38963 0)
			(unlocked yes)
			(layer "F.SilkS")
			(effects
				(font
					(size 0.7874 0.5842)
					(thickness 0.1524)
				)
			)
		)
		(property "Value" "VAL*"
			(at 0.02032 2.13233 180)
			(unlocked yes)
			(layer "F.Fab")
			(hide yes)
			(effects
				(font
					(size 0.7874 0.5842)
					(thickness 0.1524)
				)
			)
		)
		(property "Tolerance" "TOL*"
			(at 0.044704 3.05435 180)
			(unlocked yes)
			(layer "Cmts.User")
			(hide yes)
			(effects
				(font
					(size 0.7874 0.5842)
					(thickness 0.1524)
				)
			)
		)
		(property "User Part Number" "PARTNUM*"
			(at 0.02032 4.024884 180)
			(unlocked yes)
			(layer "Cmts.User")
			(hide yes)
			(effects
				(font
					(size 0.7874 0.5842)
					(thickness 0.1524)
				)
			)
		)
		(property "Device Type" "RESISTOR-G155-14701-01,4.7KOHMA"
			(at 0.008382 1.210564 180)
			(unlocked yes)
			(layer "F.Fab")
			(hide yes)
			(effects
				(font
					(size 0.7874 0.5842)
					(thickness 0.1524)
				)
			)
		)
		(duplicate_pad_numbers_are_jumpers no)
		(fp_line
			(start 1.143 0.5588)
			(end 1.143 -0.5588)
			(stroke
				(width 0.1)
				(type default)
			)
			(layer "F.SilkS")
		)
		(fp_line
			(start 1.143 -0.5588)
			(end -1.143 -0.5588)
			(stroke
				(width 0.1)
				(type default)
			)
			(layer "F.SilkS")
		)
		(fp_line
			(start -1.143 0.5588)
			(end 1.143 0.5588)
			(stroke
				(width 0.1)
				(type default)
			)
			(layer "F.SilkS")
		)
		(fp_line
			(start -1.143 -0.5588)
			(end -1.143 0.5588)
			(stroke
				(width 0.1)
				(type default)
			)
			(layer "F.SilkS")
		)
		(fp_poly
			(pts
				(xy -1.143 0.5588) (xy 1.143 0.5588) (xy 1.143 -0.5588) (xy -1.143 -0.5588)
			)
			(stroke
				(width 0)
				(type default)
			)
			(fill no)
			(layer "F.CrtYd")
		)
		(fp_line
			(start 0.508 0.3048)
			(end 0.508 -0.3048)
			(stroke
				(width 0.1)
				(type default)
			)
			(layer "F.Fab")
		)
		(fp_line
			(start 0.508 -0.3048)
			(end -0.508 -0.3048)
			(stroke
				(width 0.1)
				(type default)
			)
			(layer "F.Fab")
		)
		(fp_line
			(start -0.508 0.3048)
			(end 0.508 0.3048)
			(stroke
				(width 0.1)
				(type default)
			)
			(layer "F.Fab")
		)
		(fp_line
			(start -0.508 -0.3048)
			(end -0.508 0.3048)
			(stroke
				(width 0.1)
				(type default)
			)
			(layer "F.Fab")
		)
		(pad "1" smd rect
			(at -0.5334 0 180)
			(size 0.7112 0.6096)
			(layers "F.Cu" "F.Mask" "F.Paste")
			(net "XP3R3V_FPGA")
		)
		(pad "2" smd rect
			(at 0.5334 0 180)
			(size 0.7112 0.6096)
			(layers "F.Cu" "F.Mask" "F.Paste")
			(net "RGB_LED_SHUTDOWN_N")
		)
		(zone
			(layer "F.Cu")
			(hatch none 0.5)
			(connect_pads
				(clearance 0)
			)
			(min_thickness 0.25)
			(keepout
				(tracks allowed)
				(vias not_allowed)
				(pads allowed)
				(copperpour not_allowed)
				(footprints allowed)
			)
			(placement
				(enabled no)
				(sheetname "")
			)
			(fill
				(thermal_gap 0.5)
				(thermal_bridge_width 0.5)
				(island_removal_mode 0)
			)
			(polygon
				(pts
					(xy 111.2012 -98.4758) (xy 111.0488 -98.4758) (xy 111.0488 -97.8662) (xy 111.2012 -97.8662)
				)
			)
		)
		(zone
			(layer "F.Cu")
			(hatch none 0.5)
			(connect_pads
				(clearance 0)
			)
			(min_thickness 0.25)
			(keepout
				(tracks not_allowed)
				(vias allowed)
				(pads allowed)
				(copperpour not_allowed)
				(footprints allowed)
			)
			(placement
				(enabled no)
				(sheetname "")
			)
			(fill
				(thermal_gap 0.5)
				(thermal_bridge_width 0.5)
				(island_removal_mode 0)
			)
			(polygon
				(pts
					(xy 111.2012 -98.4758) (xy 111.0488 -98.4758) (xy 111.0488 -97.8662) (xy 111.2012 -97.8662)
				)
			)
		)
	)
	(footprint ""
		(layer "F.Cu")
		(at 150.749 -27.432)
		(property "Reference" "R407"
			(at -0.762 -2.11963 0)
			(unlocked yes)
			(layer "F.SilkS")
			(effects
				(font
					(size 0.7874 0.5842)
					(thickness 0.1524)
				)
			)
		)
		(property "Value" "VAL*"
			(at 0.02032 2.13233 0)
			(unlocked yes)
			(layer "F.Fab")
			(hide yes)
			(effects
				(font
					(size 0.7874 0.5842)
					(thickness 0.1524)
				)
			)
		)
		(property "Tolerance" "TOL*"
			(at 0.044704 3.05435 0)
			(unlocked yes)
			(layer "Cmts.User")
			(hide yes)
			(effects
				(font
					(size 0.7874 0.5842)
					(thickness 0.1524)
				)
			)
		)
		(property "User Part Number" "PARTNUM*"
			(at 0.02032 4.024884 0)
			(unlocked yes)
			(layer "Cmts.User")
			(hide yes)
			(effects
				(font
					(size 0.7874 0.5842)
					(thickness 0.1524)
				)
			)
		)
		(property "Device Type" "RESISTOR-G155-133R0-01,33OHM,1%"
			(at 0.008382 1.210564 0)
			(unlocked yes)
			(layer "F.Fab")
			(hide yes)
			(effects
				(font
					(size 0.7874 0.5842)
					(thickness 0.1524)
				)
			)
		)
		(duplicate_pad_numbers_are_jumpers no)
		(fp_line
			(start -1.143 -0.5588)
			(end -1.143 0.5588)
			(stroke
				(width 0.1)
				(type default)
			)
			(layer "F.SilkS")
		)
		(fp_line
			(start -1.143 0.5588)
			(end 1.143 0.5588)
			(stroke
				(width 0.1)
				(type default)
			)
			(layer "F.SilkS")
		)
		(fp_line
			(start 1.143 -0.5588)
			(end -1.143 -0.5588)
			(stroke
				(width 0.1)
				(type default)
			)
			(layer "F.SilkS")
		)
		(fp_line
			(start 1.143 0.5588)
			(end 1.143 -0.5588)
			(stroke
				(width 0.1)
				(type default)
			)
			(layer "F.SilkS")
		)
		(fp_rect
			(start -1.143 0.5588)
			(end 1.143 -0.5588)
			(stroke
				(width 0)
				(type default)
			)
			(fill no)
			(layer "F.CrtYd")
		)
		(fp_line
			(start -0.508 -0.3048)
			(end -0.508 0.3048)
			(stroke
				(width 0.1)
				(type default)
			)
			(layer "F.Fab")
		)
		(fp_line
			(start -0.508 0.3048)
			(end 0.508 0.3048)
			(stroke
				(width 0.1)
				(type default)
			)
			(layer "F.Fab")
		)
		(fp_line
			(start 0.508 -0.3048)
			(end -0.508 -0.3048)
			(stroke
				(width 0.1)
				(type default)
			)
			(layer "F.Fab")
		)
		(fp_line
			(start 0.508 0.3048)
			(end 0.508 -0.3048)
			(stroke
				(width 0.1)
				(type default)
			)
			(layer "F.Fab")
		)
		(pad "1" smd rect
			(at -0.5334 0)
			(size 0.7112 0.6096)
			(layers "F.Cu" "F.Mask" "F.Paste")
			(net "LM75B_I2C_SDA")
		)
		(pad "2" smd rect
			(at 0.5334 0)
			(size 0.7112 0.6096)
			(layers "F.Cu" "F.Mask" "F.Paste")
			(net "R_LM75B_3_I2C_SDA")
		)
		(zone
			(layer "F.Cu")
			(hatch none 0.5)
			(connect_pads
				(clearance 0)
			)
			(min_thickness 0.25)
			(keepout
				(tracks not_allowed)
				(vias allowed)
				(pads allowed)
				(copperpour not_allowed)
				(footprints allowed)
			)
			(placement
				(enabled no)
				(sheetname "")
			)
			(fill
				(thermal_gap 0.5)
				(thermal_bridge_width 0.5)
				(island_removal_mode 0)
			)
			(polygon
				(pts
					(xy 150.6728 -27.1272) (xy 150.8252 -27.1272) (xy 150.8252 -27.7368) (xy 150.6728 -27.7368)
				)
			)
		)
		(zone
			(layer "F.Cu")
			(hatch none 0.5)
			(connect_pads
				(clearance 0)
			)
			(min_thickness 0.25)
			(keepout
				(tracks allowed)
				(vias not_allowed)
				(pads allowed)
				(copperpour not_allowed)
				(footprints allowed)
			)
			(placement
				(enabled no)
				(sheetname "")
			)
			(fill
				(thermal_gap 0.5)
				(thermal_bridge_width 0.5)
				(island_removal_mode 0)
			)
			(polygon
				(pts
					(xy 150.6728 -27.1272) (xy 150.8252 -27.1272) (xy 150.8252 -27.7368) (xy 150.6728 -27.7368)
				)
			)
		)
	)
)
